FILE NAME: R4006-B0001-02_R01_BRD.ZIP

ITEM DESCRIPTION:    BOARD FILE
FILE NAME:     R4006-B0001-02_R01.BRD
SCHEMATIC IMPORTED VERSION:  \\SHACOMM01\shared\Design Repository\FB_Time card\2.Electrical\[R4006-B0001-01]_[Timing card base board]\A2\Schematic\A2R01
                             DVT_timecard_0910_23_Feb_22.zip
FILE DATE:     2022- 2-25
